# BASEBOARD_FAB2 (Tioga Pass) — schematic netlist excerpt (pin names and nets, part order shuffled) for the footprints in the layout excerpt that follows; sources: Cadence DE-HDL packaged netlist, KiCad conversion of Wiwynn_Tioga_Pass_MB.brd

C3P52  CAP_A  0.1UF 16V 10% X7R  pkg 0402V  page 192 : A = P3V3_STBY ; B = GND
C1R29  CAP_A  0.1UF 16V 10% X7R  pkg 0402V  page 139 : A = P1V5_LAN ; B = GND
R1M3  RES  100.0 1% CHIP  pkg 0402  page 112 : A = PVCCIO_CPU0 ; B = XDP_CPU_PRDY_N

(kicad_pcb
	(version 20260206)
	(generator "pcbnew")
	(generator_version "10.0")
	(general
		(thickness 1.6)
		(legacy_teardrops no)
	)
	(paper "A4")
	(title_block
		(title "Wiwynn_Tioga_Pass_MB.brd")
		(comment 1 "Tioga Pass / footprints 4671-4673 of 4770")
	)
	(layers
		(0 "F.Cu" signal "TOP")
		(4 "In1.Cu" signal "L2GND")
		(6 "In2.Cu" signal "L3")
		(8 "In3.Cu" signal "L4GND")
		(10 "In4.Cu" signal "L5")
		(12 "In5.Cu" signal "L6GND")
		(14 "In6.Cu" signal "L7VCC")
		(16 "In7.Cu" signal "L8VCC")
		(18 "In8.Cu" signal "L9GND")
		(20 "In9.Cu" signal "L10")
		(22 "In10.Cu" signal "L11GND")
		(24 "In11.Cu" signal "L12")
		(26 "In12.Cu" signal "L13GND")
		(2 "B.Cu" signal "BOTTOM")
		(9 "F.Adhes" user "F.Adhesive")
		(11 "B.Adhes" user "B.Adhesive")
		(13 "F.Paste" user "Package Geometry/Pastemask Top")
		(15 "B.Paste" user "Package Geometry/Pastemask Bottom")
		(5 "F.SilkS" user "Ref Des/Silkscreen Top")
		(7 "B.SilkS" user "Ref Des/Silkscreen Bottom")
		(1 "F.Mask" user "Board Geometry/Soldermask Top")
		(3 "B.Mask" user "Board Geometry/Soldermask Bottom")
		(17 "Dwgs.User" user "User.Drawings")
		(19 "Cmts.User" user "User.Comments")
		(21 "Eco1.User" user "User.Eco1")
		(23 "Eco2.User" user "User.Eco2")
		(25 "Edge.Cuts" user "Board Geometry/Outline")
		(27 "Margin" user)
		(31 "F.CrtYd" user "Package Geometry/Place Bound Top")
		(29 "B.CrtYd" user "Package Geometry/Place Bound Bottom")
		(35 "F.Fab" user "Ref Des/Assembly Top")
		(33 "B.Fab" user "Ref Des/Assembly Bottom")
	)
	(footprint ""
		(layer "B.Cu")
		(at 376.344688 -77.096366 180)
		(property "Reference" "C3P52"
			(at 0 0 0)
			(layer "B.SilkS")
			(hide yes)
			(effects
				(font
					(size 1.27 1.27)
				)
				(justify mirror)
			)
		)
		(property "Value" ""
			(at 0 0 0)
			(layer "B.Fab")
			(effects
				(font
					(size 1.27 1.27)
				)
				(justify mirror)
			)
		)
		(duplicate_pad_numbers_are_jumpers no)
		(fp_rect
			(start 0.2794 0.9144)
			(end -0.2794 -0.1143)
			(stroke
				(width 0)
				(type default)
			)
			(fill no)
			(layer "B.CrtYd")
		)
		(fp_line
			(start 0.2794 0.9144)
			(end 0.2794 -0.1143)
			(stroke
				(width 0.1)
				(type default)
			)
			(layer "B.Fab")
		)
		(fp_line
			(start 0.2794 -0.1143)
			(end -0.2794 -0.1143)
			(stroke
				(width 0.1)
				(type default)
			)
			(layer "B.Fab")
		)
		(fp_line
			(start -0.2794 0.9144)
			(end 0.2794 0.9144)
			(stroke
				(width 0.1)
				(type default)
			)
			(layer "B.Fab")
		)
		(fp_line
			(start -0.2794 -0.1143)
			(end -0.2794 0.9144)
			(stroke
				(width 0.1)
				(type default)
			)
			(layer "B.Fab")
		)
		(pad "1" smd custom
			(at 0 0 90)
			(size 0.10414 0.10414)
			(layers "B.Cu" "B.Mask" "B.Paste")
			(net "P3V3_STBY")
			(options
				(clearance outline)
				(anchor circle)
			)
			(primitives
				(gr_poly
					(pts
						(xy -0.20828 -0.08636) (xy -0.20828 0.08636) (xy -0.08636 0.20828) (xy 0.086614 0.20828) (xy 0.20828 0.086614)
						(xy 0.20828 -0.08636) (xy 0.08636 -0.20828) (xy -0.08636 -0.20828)
					)
					(width 0)
					(fill yes)
				)
			)
		)
		(pad "2" smd custom
			(at 0 0.8001 90)
			(size 0.10414 0.10414)
			(layers "B.Cu" "B.Mask" "B.Paste")
			(net "GND")
			(options
				(clearance outline)
				(anchor circle)
			)
			(primitives
				(gr_poly
					(pts
						(xy -0.20828 -0.08636) (xy -0.20828 0.08636) (xy -0.08636 0.20828) (xy 0.086614 0.20828) (xy 0.20828 0.086614)
						(xy 0.20828 -0.08636) (xy 0.08636 -0.20828) (xy -0.08636 -0.20828)
					)
					(width 0)
					(fill yes)
				)
			)
		)
		(zone
			(layer "B.Cu")
			(hatch none 0.5)
			(connect_pads
				(clearance 0)
			)
			(min_thickness 0.25)
			(keepout
				(tracks not_allowed)
				(vias allowed)
				(pads allowed)
				(copperpour not_allowed)
				(footprints allowed)
			)
			(placement
				(enabled no)
				(sheetname "")
			)
			(fill
				(thermal_gap 0.5)
				(thermal_bridge_width 0.5)
				(island_removal_mode 0)
			)
			(polygon
				(pts
					(xy 376.257058 -77.305916) (xy 376.257058 -77.686916) (xy 376.432318 -77.686916) (xy 376.432572 -77.305916)
				)
			)
		)
		(zone
			(layer "B.Cu")
			(hatch none 0.5)
			(connect_pads
				(clearance 0)
			)
			(min_thickness 0.25)
			(keepout
				(tracks allowed)
				(vias not_allowed)
				(pads allowed)
				(copperpour not_allowed)
				(footprints allowed)
			)
			(placement
				(enabled no)
				(sheetname "")
			)
			(fill
				(thermal_gap 0.5)
				(thermal_bridge_width 0.5)
				(island_removal_mode 0)
			)
			(polygon
				(pts
					(xy 376.257058 -77.305916) (xy 376.257058 -77.686916) (xy 376.432318 -77.686916) (xy 376.432572 -77.305916)
				)
			)
		)
	)
	(footprint ""
		(layer "B.Cu")
		(at 461.658208 -132.842254 90)
		(property "Reference" "R1M3"
			(at 0 0 90)
			(layer "B.SilkS")
			(hide yes)
			(effects
				(font
					(size 1.27 1.27)
				)
				(justify mirror)
			)
		)
		(property "Value" ""
			(at 0 0 90)
			(layer "B.Fab")
			(effects
				(font
					(size 1.27 1.27)
				)
				(justify mirror)
			)
		)
		(duplicate_pad_numbers_are_jumpers no)
		(fp_poly
			(pts
				(xy 0.2794 -0.1016) (xy -0.2794 -0.1016) (xy -0.2794 0.9906) (xy 0.2794 0.9906)
			)
			(stroke
				(width 0)
				(type default)
			)
			(fill no)
			(layer "B.CrtYd")
		)
		(fp_line
			(start 0.2794 -0.1016)
			(end 0.2794 0.9906)
			(stroke
				(width 0.1)
				(type default)
			)
			(layer "B.Fab")
		)
		(fp_line
			(start -0.2794 -0.1016)
			(end 0.2794 -0.1016)
			(stroke
				(width 0.1)
				(type default)
			)
			(layer "B.Fab")
		)
		(fp_line
			(start 0.2794 0.9906)
			(end -0.2794 0.9906)
			(stroke
				(width 0.1)
				(type default)
			)
			(layer "B.Fab")
		)
		(fp_line
			(start -0.2794 0.9906)
			(end -0.2794 -0.1016)
			(stroke
				(width 0.1)
				(type default)
			)
			(layer "B.Fab")
		)
		(pad "1" smd rect
			(at 0 0 270)
			(size 0.508 0.508)
			(layers "B.Cu" "B.Mask" "B.Paste")
			(net "PVCCIO_CPU0")
		)
		(pad "2" smd rect
			(at 0 0.889 270)
			(size 0.508 0.508)
			(layers "B.Cu" "B.Mask" "B.Paste")
			(net "XDP_CPU_PRDY_N")
		)
		(zone
			(layer "B.Cu")
			(hatch none 0.5)
			(connect_pads
				(clearance 0)
			)
			(min_thickness 0.25)
			(keepout
				(tracks allowed)
				(vias not_allowed)
				(pads allowed)
				(copperpour not_allowed)
				(footprints allowed)
			)
			(placement
				(enabled no)
				(sheetname "")
			)
			(fill
				(thermal_gap 0.5)
				(thermal_bridge_width 0.5)
				(island_removal_mode 0)
			)
			(polygon
				(pts
					(xy 461.912208 -133.096254) (xy 461.912208 -132.588254) (xy 462.293208 -132.588254) (xy 462.293208 -133.096254)
				)
			)
		)
		(zone
			(layer "B.Cu")
			(hatch none 0.5)
			(connect_pads
				(clearance 0)
			)
			(min_thickness 0.25)
			(keepout
				(tracks not_allowed)
				(vias allowed)
				(pads allowed)
				(copperpour not_allowed)
				(footprints allowed)
			)
			(placement
				(enabled no)
				(sheetname "")
			)
			(fill
				(thermal_gap 0.5)
				(thermal_bridge_width 0.5)
				(island_removal_mode 0)
			)
			(polygon
				(pts
					(xy 462.293208 -133.096254) (xy 462.293208 -132.588254) (xy 461.912208 -132.588254) (xy 461.912208 -133.096254)
				)
			)
		)
	)
	(footprint ""
		(layer "B.Cu")
		(at 479.9965 -44.323 90)
		(property "Reference" "C1R29"
			(at 0 0 90)
			(layer "B.SilkS")
			(hide yes)
			(effects
				(font
					(size 1.27 1.27)
				)
				(justify mirror)
			)
		)
		(property "Value" ""
			(at 0 0 90)
			(layer "B.Fab")
			(effects
				(font
					(size 1.27 1.27)
				)
				(justify mirror)
			)
		)
		(duplicate_pad_numbers_are_jumpers no)
		(fp_poly
			(pts
				(xy -0.3048 -0.1016) (xy -0.3048 0.9906) (xy 0.3048 0.9906) (xy 0.3048 -0.1016)
			)
			(stroke
				(width 0)
				(type default)
			)
			(fill no)
			(layer "B.CrtYd")
		)
		(fp_line
			(start 0.3048 -0.1016)
			(end 0.3048 0.9906)
			(stroke
				(width 0.1)
				(type default)
			)
			(layer "B.Fab")
		)
		(fp_line
			(start -0.3048 -0.1016)
			(end 0.3048 -0.1016)
			(stroke
				(width 0.1)
				(type default)
			)
			(layer "B.Fab")
		)
		(fp_line
			(start 0.3048 0.9906)
			(end -0.3048 0.9906)
			(stroke
				(width 0.1)
				(type default)
			)
			(layer "B.Fab")
		)
		(fp_line
			(start -0.3048 0.9906)
			(end -0.3048 -0.1016)
			(stroke
				(width 0.1)
				(type default)
			)
			(layer "B.Fab")
		)
		(pad "1" smd rect
			(at 0 0 270)
			(size 0.508 0.508)
			(layers "B.Cu" "B.Mask" "B.Paste")
			(net "P1V5_LAN")
		)
		(pad "2" smd rect
			(at 0 0.889 270)
			(size 0.508 0.508)
			(layers "B.Cu" "B.Mask" "B.Paste")
			(net "GND")
		)
		(zone
			(layer "B.Cu")
			(hatch none 0.5)
			(connect_pads
				(clearance 0)
			)
			(min_thickness 0.25)
			(keepout
				(tracks allowed)
				(vias not_allowed)
				(pads allowed)
				(copperpour not_allowed)
				(footprints allowed)
			)
			(placement
				(enabled no)
				(sheetname "")
			)
			(fill
				(thermal_gap 0.5)
				(thermal_bridge_width 0.5)
				(island_removal_mode 0)
			)
			(polygon
				(pts
					(xy 480.2505 -44.577) (xy 480.2505 -44.069) (xy 480.6315 -44.069) (xy 480.6315 -44.577)
				)
			)
		)
		(zone
			(layer "B.Cu")
			(hatch none 0.5)
			(connect_pads
				(clearance 0)
			)
			(min_thickness 0.25)
			(keepout
				(tracks not_allowed)
				(vias allowed)
				(pads allowed)
				(copperpour not_allowed)
				(footprints allowed)
			)
			(placement
				(enabled no)
				(sheetname "")
			)
			(fill
				(thermal_gap 0.5)
				(thermal_bridge_width 0.5)
				(island_removal_mode 0)
			)
			(polygon
				(pts
					(xy 480.6315 -44.577) (xy 480.6315 -44.069) (xy 480.2505 -44.069) (xy 480.2505 -44.577)
				)
			)
		)
	)
)
